# T6G (Grand Teton) — schematic netlist excerpt (pin names and nets, part order shuffled) for the footprints in the layout excerpt that follows; sources: Cadence DE-HDL packaged netlist, KiCad conversion of 04192023_DAF0TMB3IC0_F0TG_MB_C_brd_V02_OCP.brd

PR402  Q_RES  49.9 1% CHIP  pkg 0402LF  page 226 : A = PVDD18_S5_P1 ; B = PVDD18_S5_P1_FB_RC
R4068  Q_RES  10K 1% CHIP  pkg 0402LF  page 134 : A = P12V_AUX ; B = P12V_OCP_1_EN_G
C814  Q_CAP_DIFFBUS  DIFF BUS_0.22UF 6.3V 20% X6S  pkg C0201  page 65 : \1\ = P5E_CPU1_P0_TX_C_DN<11> ; \2\ = P5E_CPU1_P0_TX_DN<11>

(kicad_pcb
	(version 20260206)
	(generator "pcbnew")
	(generator_version "10.0")
	(general
		(thickness 1.6)
		(legacy_teardrops no)
	)
	(paper "A4")
	(title_block
		(title "04192023_DAF0TMB3IC0_F0TG_MB_C_brd_V02_OCP.brd")
		(comment 1 "Grand Teton / footprints 1072-1074 of 8354")
	)
	(layers
		(0 "F.Cu" signal "TOP")
		(4 "In1.Cu" signal "GND")
		(6 "In2.Cu" signal "IN1")
		(8 "In3.Cu" signal "GND1")
		(10 "In4.Cu" signal "IN2")
		(12 "In5.Cu" signal "GND2")
		(14 "In6.Cu" signal "IN3")
		(16 "In7.Cu" signal "GND3")
		(18 "In8.Cu" signal "VCC")
		(20 "In9.Cu" signal "VCC1")
		(22 "In10.Cu" signal "GND4")
		(24 "In11.Cu" signal "IN4")
		(26 "In12.Cu" signal "GND5")
		(28 "In13.Cu" signal "IN5")
		(30 "In14.Cu" signal "GND6")
		(32 "In15.Cu" signal "IN6")
		(34 "In16.Cu" signal "GND7")
		(2 "B.Cu" signal "BOTTOM")
		(9 "F.Adhes" user "F.Adhesive")
		(11 "B.Adhes" user "B.Adhesive")
		(13 "F.Paste" user "Package Geometry/Pastemask Top")
		(15 "B.Paste" user "Package Geometry/Pastemask Bottom")
		(5 "F.SilkS" user "Ref Des/Silkscreen Top")
		(7 "B.SilkS" user "Ref Des/Silkscreen Bottom")
		(1 "F.Mask" user "Board Geometry/Soldermask Top")
		(3 "B.Mask" user "Board Geometry/Soldermask Bottom")
		(17 "Dwgs.User" user "User.Drawings")
		(19 "Cmts.User" user "User.Comments")
		(21 "Eco1.User" user "User.Eco1")
		(23 "Eco2.User" user "User.Eco2")
		(25 "Edge.Cuts" user "Board Geometry/Outline")
		(27 "Margin" user)
		(31 "F.CrtYd" user "Package Geometry/Place Bound Top")
		(29 "B.CrtYd" user "Package Geometry/Place Bound Bottom")
		(35 "F.Fab" user "Ref Des/Assembly Top")
		(33 "B.Fab" user "Ref Des/Assembly Bottom")
	)
	(footprint ""
		(layer "F.Cu")
		(at 58.08345 -143.664686 -90)
		(property "Reference" "PR402"
			(at 0 0 270)
			(layer "F.SilkS")
			(hide yes)
			(effects
				(font
					(size 1.27 1.27)
				)
			)
		)
		(property "Value" ""
			(at 0 0 270)
			(layer "F.Fab")
			(effects
				(font
					(size 1.27 1.27)
				)
			)
		)
		(duplicate_pad_numbers_are_jumpers no)
		(fp_line
			(start -0.7874 0.4064)
			(end -0.7874 -0.4064)
			(stroke
				(width 0.1524)
				(type default)
			)
			(layer "F.SilkS")
		)
		(fp_line
			(start 0.7874 0.4064)
			(end -0.7874 0.4064)
			(stroke
				(width 0.1524)
				(type default)
			)
			(layer "F.SilkS")
		)
		(fp_line
			(start -0.7874 -0.4064)
			(end 0.7874 -0.4064)
			(stroke
				(width 0.1524)
				(type default)
			)
			(layer "F.SilkS")
		)
		(fp_line
			(start 0.7874 -0.4064)
			(end 0.7874 0.4064)
			(stroke
				(width 0.1524)
				(type default)
			)
			(layer "F.SilkS")
		)
		(fp_line
			(start -0.67945 0.3048)
			(end -0.67945 -0.305054)
			(stroke
				(width 0.1)
				(type default)
			)
			(layer "F.Fab")
		)
		(fp_line
			(start -0.12065 0.3048)
			(end -0.67945 0.3048)
			(stroke
				(width 0.1)
				(type default)
			)
			(layer "F.Fab")
		)
		(fp_line
			(start 0.120396 0.3048)
			(end 0.120396 0.2794)
			(stroke
				(width 0.1)
				(type default)
			)
			(layer "F.Fab")
		)
		(fp_line
			(start 0.67945 0.3048)
			(end 0.120396 0.3048)
			(stroke
				(width 0.1)
				(type default)
			)
			(layer "F.Fab")
		)
		(fp_line
			(start -0.12065 0.2794)
			(end -0.12065 0.3048)
			(stroke
				(width 0.1)
				(type default)
			)
			(layer "F.Fab")
		)
		(fp_line
			(start 0.120396 0.2794)
			(end -0.12065 0.2794)
			(stroke
				(width 0.1)
				(type default)
			)
			(layer "F.Fab")
		)
		(fp_line
			(start -0.12065 -0.2794)
			(end 0.12065 -0.2794)
			(stroke
				(width 0.1)
				(type default)
			)
			(layer "F.Fab")
		)
		(fp_line
			(start 0.12065 -0.2794)
			(end 0.12065 -0.3048)
			(stroke
				(width 0.1)
				(type default)
			)
			(layer "F.Fab")
		)
		(fp_line
			(start 0.12065 -0.3048)
			(end 0.67945 -0.3048)
			(stroke
				(width 0.1)
				(type default)
			)
			(layer "F.Fab")
		)
		(fp_line
			(start 0.67945 -0.3048)
			(end 0.67945 0.3048)
			(stroke
				(width 0.1)
				(type default)
			)
			(layer "F.Fab")
		)
		(fp_line
			(start -0.67945 -0.305054)
			(end -0.12065 -0.305054)
			(stroke
				(width 0.1)
				(type default)
			)
			(layer "F.Fab")
		)
		(fp_line
			(start -0.12065 -0.305054)
			(end -0.12065 -0.2794)
			(stroke
				(width 0.1)
				(type default)
			)
			(layer "F.Fab")
		)
		(pad "1" smd circle
			(at -0.40005 0 270)
			(size 0 0)
			(layers "F.Cu" "F.Mask" "F.Paste")
			(net "PVDD18_S5_P1")
		)
		(pad "2" smd circle
			(at 0.40005 0 270)
			(size 0 0)
			(layers "F.Cu" "F.Mask" "F.Paste")
			(net "PVDD18_S5_P1_FB_RC")
		)
	)
	(footprint ""
		(layer "F.Cu")
		(at 462.20507 -40.226488 -90)
		(property "Reference" "R4068"
			(at 0 0 270)
			(layer "F.SilkS")
			(hide yes)
			(effects
				(font
					(size 1.27 1.27)
				)
			)
		)
		(property "Value" ""
			(at 0 0 270)
			(layer "F.Fab")
			(effects
				(font
					(size 1.27 1.27)
				)
			)
		)
		(duplicate_pad_numbers_are_jumpers no)
		(fp_line
			(start -0.7874 0.4064)
			(end -0.7874 -0.4064)
			(stroke
				(width 0.1524)
				(type default)
			)
			(layer "F.SilkS")
		)
		(fp_line
			(start 0.7874 0.4064)
			(end -0.7874 0.4064)
			(stroke
				(width 0.1524)
				(type default)
			)
			(layer "F.SilkS")
		)
		(fp_line
			(start -0.7874 -0.4064)
			(end 0.7874 -0.4064)
			(stroke
				(width 0.1524)
				(type default)
			)
			(layer "F.SilkS")
		)
		(fp_line
			(start 0.7874 -0.4064)
			(end 0.7874 0.4064)
			(stroke
				(width 0.1524)
				(type default)
			)
			(layer "F.SilkS")
		)
		(fp_line
			(start -0.67945 0.3048)
			(end -0.67945 -0.305054)
			(stroke
				(width 0.1)
				(type default)
			)
			(layer "F.Fab")
		)
		(fp_line
			(start -0.12065 0.3048)
			(end -0.67945 0.3048)
			(stroke
				(width 0.1)
				(type default)
			)
			(layer "F.Fab")
		)
		(fp_line
			(start 0.120396 0.3048)
			(end 0.120396 0.2794)
			(stroke
				(width 0.1)
				(type default)
			)
			(layer "F.Fab")
		)
		(fp_line
			(start 0.67945 0.3048)
			(end 0.120396 0.3048)
			(stroke
				(width 0.1)
				(type default)
			)
			(layer "F.Fab")
		)
		(fp_line
			(start -0.12065 0.2794)
			(end -0.12065 0.3048)
			(stroke
				(width 0.1)
				(type default)
			)
			(layer "F.Fab")
		)
		(fp_line
			(start 0.120396 0.2794)
			(end -0.12065 0.2794)
			(stroke
				(width 0.1)
				(type default)
			)
			(layer "F.Fab")
		)
		(fp_line
			(start -0.12065 -0.2794)
			(end 0.12065 -0.2794)
			(stroke
				(width 0.1)
				(type default)
			)
			(layer "F.Fab")
		)
		(fp_line
			(start 0.12065 -0.2794)
			(end 0.12065 -0.3048)
			(stroke
				(width 0.1)
				(type default)
			)
			(layer "F.Fab")
		)
		(fp_line
			(start 0.12065 -0.3048)
			(end 0.67945 -0.3048)
			(stroke
				(width 0.1)
				(type default)
			)
			(layer "F.Fab")
		)
		(fp_line
			(start 0.67945 -0.3048)
			(end 0.67945 0.3048)
			(stroke
				(width 0.1)
				(type default)
			)
			(layer "F.Fab")
		)
		(fp_line
			(start -0.67945 -0.305054)
			(end -0.12065 -0.305054)
			(stroke
				(width 0.1)
				(type default)
			)
			(layer "F.Fab")
		)
		(fp_line
			(start -0.12065 -0.305054)
			(end -0.12065 -0.2794)
			(stroke
				(width 0.1)
				(type default)
			)
			(layer "F.Fab")
		)
		(pad "1" smd circle
			(at -0.40005 0 270)
			(size 0 0)
			(layers "F.Cu" "F.Mask" "F.Paste")
			(net "P12V_AUX")
		)
		(pad "2" smd circle
			(at 0.40005 0 270)
			(size 0 0)
			(layers "F.Cu" "F.Mask" "F.Paste")
			(net "P12V_OCP_1_EN_G")
		)
	)
	(footprint ""
		(layer "F.Cu")
		(at 64.325754 -373.03583 -90)
		(property "Reference" "C814"
			(at 0 0 270)
			(layer "F.SilkS")
			(hide yes)
			(effects
				(font
					(size 1.27 1.27)
				)
			)
		)
		(property "Value" ""
			(at 0 0 270)
			(layer "F.Fab")
			(effects
				(font
					(size 1.27 1.27)
				)
			)
		)
		(duplicate_pad_numbers_are_jumpers no)
		(fp_line
			(start -0.299974 0.150114)
			(end -0.299974 -0.150114)
			(stroke
				(width 0.1)
				(type default)
			)
			(layer "F.Fab")
		)
		(fp_line
			(start 0.299974 0.150114)
			(end -0.299974 0.150114)
			(stroke
				(width 0.1)
				(type default)
			)
			(layer "F.Fab")
		)
		(fp_line
			(start -0.299974 -0.150114)
			(end 0.299974 -0.150114)
			(stroke
				(width 0.1)
				(type default)
			)
			(layer "F.Fab")
		)
		(fp_line
			(start 0.299974 -0.150114)
			(end 0.299974 0.150114)
			(stroke
				(width 0.1)
				(type default)
			)
			(layer "F.Fab")
		)
		(pad "1" smd rect
			(at -0.2667 0 270)
			(size 0.3048 0.381)
			(layers "F.Cu" "F.Mask" "F.Paste")
			(net "P5E_CPU1_P0_TX_C_DN<11>")
		)
		(pad "2" smd rect
			(at 0.2667 0 270)
			(size 0.3048 0.381)
			(layers "F.Cu" "F.Mask" "F.Paste")
			(net "P5E_CPU1_P0_TX_DN<11>")
		)
	)
)
